(kicad_pcb
	(version 20241229)
	(generator "pcbnew")
	(generator_version "9.0")
	(general
		(thickness 1.294)
		(legacy_teardrops no)
	)
	(paper "A3")
	(title_block
		(title "Kintex 410T devboard")
		(date "2024-04-03")
		(rev "1.1.2")
		(comment 9 "footprint 224 of 975 (U5), pads 1-78 of 78")
	)
	(layers
		(0 "F.Cu" mixed)
		(4 "In1.Cu" power)
		(6 "In2.Cu" power)
		(8 "In3.Cu" mixed)
		(10 "In4.Cu" power)
		(12 "In5.Cu" mixed)
		(14 "In6.Cu" power)
		(16 "In7.Cu" mixed)
		(18 "In8.Cu" power)
		(2 "B.Cu" mixed)
		(9 "F.Adhes" user "F.Adhesive")
		(11 "B.Adhes" user "B.Adhesive")
		(13 "F.Paste" user)
		(15 "B.Paste" user)
		(5 "F.SilkS" user "F.Silkscreen")
		(7 "B.SilkS" user "B.Silkscreen")
		(1 "F.Mask" user)
		(3 "B.Mask" user)
		(17 "Dwgs.User" user "User.Drawings")
		(19 "Cmts.User" user "User.Comments")
		(21 "Eco1.User" user "User.Eco1")
		(23 "Eco2.User" user "User.Eco2")
		(25 "Edge.Cuts" user)
		(27 "Margin" user)
		(31 "F.CrtYd" user "F.Courtyard")
		(29 "B.CrtYd" user "B.Courtyard")
		(35 "F.Fab" user)
		(33 "B.Fab" user)
	)
	(footprint "antmicro-footprints:Micron_FBGA-78"
		(layer "F.Cu")
		(at 169.2 145.6 -90)
		(property "Reference" "U5"
			(at -4.27 -6.51 90)
			(layer "F.SilkS")
			(effects
				(font
					(size 0.7 0.7)
					(thickness 0.15)
				)
				(justify right bottom)
			)
		)
		(property "Value" "MT41K512M8DA"
			(at -4.37 6.69 90)
			(layer "F.Fab")
			(effects
				(font
					(size 0.7 0.7)
					(thickness 0.15)
				)
				(justify right bottom)
			)
		)
		(property "Description" "SDRAM - DDR3L Memory IC 4Gbit Parallel 933 MHz 20 ns 78-FBGA (8x10.5)"
			(at 0 0 270)
			(layer "F.Fab")
			(hide yes)
			(effects
				(font
					(size 1.27 1.27)
					(thickness 0.15)
				)
			)
		)
		(property "Author" "Antmicro"
			(at 23.6 314.8 0)
			(layer "F.Fab")
			(hide yes)
			(effects
				(font
					(size 1 1)
					(thickness 0.15)
				)
			)
		)
		(property "License" "Apache-2.0"
			(at 23.6 314.8 0)
			(layer "F.Fab")
			(hide yes)
			(effects
				(font
					(size 1 1)
					(thickness 0.15)
				)
			)
		)
		(property "MPN" "MT41K512M8DA-107 XIT:P TR"
			(at 23.6 314.8 0)
			(layer "F.Fab")
			(hide yes)
			(effects
				(font
					(size 1 1)
					(thickness 0.15)
				)
			)
		)
		(property "Manufacturer" "Micron Technology"
			(at 23.6 314.8 0)
			(layer "F.Fab")
			(hide yes)
			(effects
				(font
					(size 1 1)
					(thickness 0.15)
				)
			)
		)
		(sheetname "DRAM + SRAM")
		(sheetfile "ram.kicad_sch")
		(attr smd)
		(pad "A1" smd circle
			(at -3.202 -4.8 270)
			(size 0.43 0.43)
			(layers "F.Cu" "F.Mask" "F.Paste")
			(net 1 "GND")
			(pinfunction "VSS")
			(pintype "passive")
		)
		(pad "A2" smd circle
			(at -2.4 -4.8 270)
			(size 0.43 0.43)
			(layers "F.Cu" "F.Mask" "F.Paste")
			(net 25 "+1V35")
			(pinfunction "VDD")
			(pintype "power_in")
		)
		(pad "A3" smd circle
			(at -1.601 -4.8 270)
			(size 0.43 0.43)
			(layers "F.Cu" "F.Mask" "F.Paste")
			(net 1134 "unconnected-(U5-NC-PadA3)")
			(pinfunction "NC")
			(pintype "no_connect")
		)
		(pad "A7" smd circle
			(at 1.6 -4.8 270)
			(size 0.43 0.43)
			(layers "F.Cu" "F.Mask" "F.Paste")
			(net 1135 "unconnected-(U5-NF{slash}TDQS#-PadA7)")
			(pinfunction "NF/TDQS#")
			(pintype "output+no_connect")
		)
		(pad "A8" smd circle
			(at 2.398 -4.8 270)
			(size 0.43 0.43)
			(layers "F.Cu" "F.Mask" "F.Paste")
			(net 1 "GND")
			(pinfunction "VSS")
			(pintype "passive")
		)
		(pad "A9" smd circle
			(at 3.2 -4.8 270)
			(size 0.43 0.43)
			(layers "F.Cu" "F.Mask" "F.Paste")
			(net 25 "+1V35")
			(pinfunction "VDD")
			(pintype "passive")
		)
		(pad "B1" smd circle
			(at -3.202 -4 270)
			(size 0.43 0.43)
			(layers "F.Cu" "F.Mask" "F.Paste")
			(net 1 "GND")
			(pinfunction "VSS")
			(pintype "passive")
		)
		(pad "B2" smd circle
			(at -2.4 -4 270)
			(size 0.43 0.43)
			(layers "F.Cu" "F.Mask" "F.Paste")
			(net 1 "GND")
			(pinfunction "VSSQ")
			(pintype "passive")
		)
		(pad "B3" smd circle
			(at -1.601 -4 270)
			(size 0.43 0.43)
			(layers "F.Cu" "F.Mask" "F.Paste")
			(net 661 "/DRAM + SRAM/DDR.DQ0")
			(pinfunction "DQ0")
			(pintype "bidirectional")
		)
		(pad "B7" smd circle
			(at 1.6 -4 270)
			(size 0.43 0.43)
			(layers "F.Cu" "F.Mask" "F.Paste")
			(net 557 "/DRAM + SRAM/DDR.DM")
			(pinfunction "DM/TDQS")
			(pintype "bidirectional")
		)
		(pad "B8" smd circle
			(at 2.398 -4 270)
			(size 0.43 0.43)
			(layers "F.Cu" "F.Mask" "F.Paste")
			(net 1 "GND")
			(pinfunction "VSSQ")
			(pintype "passive")
		)
		(pad "B9" smd circle
			(at 3.2 -4 270)
			(size 0.43 0.43)
			(layers "F.Cu" "F.Mask" "F.Paste")
			(net 25 "+1V35")
			(pinfunction "VDDQ")
			(pintype "power_in")
		)
		(pad "C1" smd circle
			(at -3.202 -3.202 270)
			(size 0.43 0.43)
			(layers "F.Cu" "F.Mask" "F.Paste")
			(net 25 "+1V35")
			(pinfunction "VDDQ")
			(pintype "passive")
		)
		(pad "C2" smd circle
			(at -2.4 -3.202 270)
			(size 0.43 0.43)
			(layers "F.Cu" "F.Mask" "F.Paste")
			(net 662 "/DRAM + SRAM/DDR.DQ2")
			(pinfunction "DQ2")
			(pintype "bidirectional")
		)
		(pad "C3" smd circle
			(at -1.601 -3.202 270)
			(size 0.43 0.43)
			(layers "F.Cu" "F.Mask" "F.Paste")
			(net 656 "/DRAM + SRAM/DDR.DQS_P")
			(pinfunction "DQS")
			(pintype "bidirectional")
		)
		(pad "C7" smd circle
			(at 1.6 -3.202 270)
			(size 0.43 0.43)
			(layers "F.Cu" "F.Mask" "F.Paste")
			(net 663 "/DRAM + SRAM/DDR.DQ1")
			(pinfunction "DQ1")
			(pintype "bidirectional")
		)
		(pad "C8" smd circle
			(at 2.398 -3.202 270)
			(size 0.43 0.43)
			(layers "F.Cu" "F.Mask" "F.Paste")
			(net 657 "/DRAM + SRAM/DDR.DQ3")
			(pinfunction "DQ3")
			(pintype "bidirectional")
		)
		(pad "C9" smd circle
			(at 3.2 -3.202 270)
			(size 0.43 0.43)
			(layers "F.Cu" "F.Mask" "F.Paste")
			(net 1 "GND")
			(pinfunction "VSSQ")
			(pintype "passive")
		)
		(pad "D1" smd circle
			(at -3.202 -2.4 270)
			(size 0.43 0.43)
			(layers "F.Cu" "F.Mask" "F.Paste")
			(net 1 "GND")
			(pinfunction "VSSQ")
			(pintype "passive")
		)
		(pad "D2" smd circle
			(at -2.4 -2.4 270)
			(size 0.43 0.43)
			(layers "F.Cu" "F.Mask" "F.Paste")
			(net 660 "/DRAM + SRAM/DDR.DQ6")
			(pinfunction "NF/DQ6")
			(pintype "bidirectional")
		)
		(pad "D3" smd circle
			(at -1.601 -2.4 270)
			(size 0.43 0.43)
			(layers "F.Cu" "F.Mask" "F.Paste")
			(net 658 "/DRAM + SRAM/DDR.DQS_N")
			(pinfunction "DQS#")
			(pintype "bidirectional")
		)
		(pad "D7" smd circle
			(at 1.6 -2.4 270)
			(size 0.43 0.43)
			(layers "F.Cu" "F.Mask" "F.Paste")
			(net 25 "+1V35")
			(pinfunction "VDD")
			(pintype "passive")
		)
		(pad "D8" smd circle
			(at 2.398 -2.4 270)
			(size 0.43 0.43)
			(layers "F.Cu" "F.Mask" "F.Paste")
			(net 1 "GND")
			(pinfunction "VSS")
			(pintype "passive")
		)
		(pad "D9" smd circle
			(at 3.2 -2.4 270)
			(size 0.43 0.43)
			(layers "F.Cu" "F.Mask" "F.Paste")
			(net 1 "GND")
			(pinfunction "VSSQ")
			(pintype "passive")
		)
		(pad "E1" smd circle
			(at -3.202 -1.601 270)
			(size 0.43 0.43)
			(layers "F.Cu" "F.Mask" "F.Paste")
			(net 11 "+0V675_VREF")
			(pinfunction "VREFDQ")
			(pintype "power_in")
		)
		(pad "E2" smd circle
			(at -2.4 -1.601 270)
			(size 0.43 0.43)
			(layers "F.Cu" "F.Mask" "F.Paste")
			(net 25 "+1V35")
			(pinfunction "VDDQ")
			(pintype "passive")
		)
		(pad "E3" smd circle
			(at -1.601 -1.601 270)
			(size 0.43 0.43)
			(layers "F.Cu" "F.Mask" "F.Paste")
			(net 655 "/DRAM + SRAM/DDR.DQ4")
			(pinfunction "NF/DQ4")
			(pintype "bidirectional")
		)
		(pad "E7" smd circle
			(at 1.6 -1.601 270)
			(size 0.43 0.43)
			(layers "F.Cu" "F.Mask" "F.Paste")
			(net 654 "/DRAM + SRAM/DDR.DQ7")
			(pinfunction "NF/DQ7")
			(pintype "bidirectional")
		)
		(pad "E8" smd circle
			(at 2.398 -1.601 270)
			(size 0.43 0.43)
			(layers "F.Cu" "F.Mask" "F.Paste")
			(net 659 "/DRAM + SRAM/DDR.DQ5")
			(pinfunction "NF/DQ5")
			(pintype "bidirectional")
		)
		(pad "E9" smd circle
			(at 3.2 -1.601 270)
			(size 0.43 0.43)
			(layers "F.Cu" "F.Mask" "F.Paste")
			(net 25 "+1V35")
			(pinfunction "VDDQ")
			(pintype "passive")
		)
		(pad "F1" smd circle
			(at -3.202 -0.802 270)
			(size 0.43 0.43)
			(layers "F.Cu" "F.Mask" "F.Paste")
			(net 1136 "unconnected-(U5-NC-PadF1)")
			(pinfunction "NC")
			(pintype "no_connect")
		)
		(pad "F2" smd circle
			(at -2.4 -0.802 270)
			(size 0.43 0.43)
			(layers "F.Cu" "F.Mask" "F.Paste")
			(net 1 "GND")
			(pinfunction "VSS")
			(pintype "passive")
		)
		(pad "F3" smd circle
			(at -1.601 -0.802 270)
			(size 0.43 0.43)
			(layers "F.Cu" "F.Mask" "F.Paste")
			(net 560 "/DRAM + SRAM/DDR.~{RAS}")
			(pinfunction "RAS#")
			(pintype "input")
		)
		(pad "F7" smd circle
			(at 1.6 -0.802 270)
			(size 0.43 0.43)
			(layers "F.Cu" "F.Mask" "F.Paste")
			(net 551 "/DRAM + SRAM/DDR.CK_P")
			(pinfunction "CK")
			(pintype "input")
		)
		(pad "F8" smd circle
			(at 2.398 -0.802 270)
			(size 0.43 0.43)
			(layers "F.Cu" "F.Mask" "F.Paste")
			(net 1 "GND")
			(pinfunction "VSS")
			(pintype "passive")
		)
		(pad "F9" smd circle
			(at 3.2 -0.802 270)
			(size 0.43 0.43)
			(layers "F.Cu" "F.Mask" "F.Paste")
			(net 1137 "unconnected-(U5-NC-PadF9)")
			(pinfunction "NC")
			(pintype "no_connect")
		)
		(pad "G1" smd circle
			(at -3.202 0 270)
			(size 0.43 0.43)
			(layers "F.Cu" "F.Mask" "F.Paste")
			(net 553 "/DRAM + SRAM/DDR.ODT")
			(pinfunction "ODT")
			(pintype "input")
		)
		(pad "G2" smd circle
			(at -2.4 0 270)
			(size 0.43 0.43)
			(layers "F.Cu" "F.Mask" "F.Paste")
			(net 25 "+1V35")
			(pinfunction "VDD")
			(pintype "passive")
		)
		(pad "G3" smd circle
			(at -1.601 0 270)
			(size 0.43 0.43)
			(layers "F.Cu" "F.Mask" "F.Paste")
			(net 559 "/DRAM + SRAM/DDR.~{CAS}")
			(pinfunction "CAS#")
			(pintype "input")
		)
		(pad "G7" smd circle
			(at 1.6 0 270)
			(size 0.43 0.43)
			(layers "F.Cu" "F.Mask" "F.Paste")
			(net 552 "/DRAM + SRAM/DDR.CK_N")
			(pinfunction "CK#")
			(pintype "input")
		)
		(pad "G8" smd circle
			(at 2.398 0 270)
			(size 0.43 0.43)
			(layers "F.Cu" "F.Mask" "F.Paste")
			(net 25 "+1V35")
			(pinfunction "VDD")
			(pintype "passive")
		)
		(pad "G9" smd circle
			(at 3.2 0 270)
			(size 0.43 0.43)
			(layers "F.Cu" "F.Mask" "F.Paste")
			(net 550 "/DRAM + SRAM/DDR.CKE")
			(pinfunction "CKE")
			(pintype "input")
		)
		(pad "H1" smd circle
			(at -3.202 0.8 270)
			(size 0.43 0.43)
			(layers "F.Cu" "F.Mask" "F.Paste")
			(net 1138 "unconnected-(U5-NC-PadH1)")
			(pinfunction "NC")
			(pintype "no_connect")
		)
		(pad "H2" smd circle
			(at -2.4 0.8 270)
			(size 0.43 0.43)
			(layers "F.Cu" "F.Mask" "F.Paste")
			(net 561 "/DRAM + SRAM/DDR.~{CS}")
			(pinfunction "CS#")
			(pintype "input")
		)
		(pad "H3" smd circle
			(at -1.601 0.8 270)
			(size 0.43 0.43)
			(layers "F.Cu" "F.Mask" "F.Paste")
			(net 558 "/DRAM + SRAM/DDR.~{WE}")
			(pinfunction "WE#")
			(pintype "input")
		)
		(pad "H7" smd circle
			(at 1.6 0.8 270)
			(size 0.43 0.43)
			(layers "F.Cu" "F.Mask" "F.Paste")
			(net 541 "/DRAM + SRAM/DDR.A10")
			(pinfunction "A10/AP")
			(pintype "input")
		)
		(pad "H8" smd circle
			(at 2.398 0.8 270)
			(size 0.43 0.43)
			(layers "F.Cu" "F.Mask" "F.Paste")
			(net 555 "/DRAM + SRAM/DDR_ZQ")
			(pinfunction "ZQ")
			(pintype "output")
		)
		(pad "H9" smd circle
			(at 3.2 0.8 270)
			(size 0.43 0.43)
			(layers "F.Cu" "F.Mask" "F.Paste")
			(net 1139 "unconnected-(U5-NC-PadH9)")
			(pinfunction "NC")
			(pintype "no_connect")
		)
		(pad "J1" smd circle
			(at -3.202 1.6 270)
			(size 0.43 0.43)
			(layers "F.Cu" "F.Mask" "F.Paste")
			(net 1 "GND")
			(pinfunction "VSS")
			(pintype "passive")
		)
		(pad "J2" smd circle
			(at -2.4 1.6 270)
			(size 0.43 0.43)
			(layers "F.Cu" "F.Mask" "F.Paste")
			(net 547 "/DRAM + SRAM/DDR.BA0")
			(pinfunction "BA0")
			(pintype "input")
		)
		(pad "J3" smd circle
			(at -1.601 1.6 270)
			(size 0.43 0.43)
			(layers "F.Cu" "F.Mask" "F.Paste")
			(net 549 "/DRAM + SRAM/DDR.BA2")
			(pinfunction "BA2")
			(pintype "input")
		)
		(pad "J7" smd circle
			(at 1.6 1.6 270)
			(size 0.43 0.43)
			(layers "F.Cu" "F.Mask" "F.Paste")
			(net 546 "/DRAM + SRAM/DDR.A15")
			(pinfunction "A15")
			(pintype "input")
		)
		(pad "J8" smd circle
			(at 2.398 1.6 270)
			(size 0.43 0.43)
			(layers "F.Cu" "F.Mask" "F.Paste")
			(net 11 "+0V675_VREF")
			(pinfunction "VREFCA")
			(pintype "power_in")
		)
		(pad "J9" smd circle
			(at 3.2 1.6 270)
			(size 0.43 0.43)
			(layers "F.Cu" "F.Mask" "F.Paste")
			(net 1 "GND")
			(pinfunction "VSS")
			(pintype "passive")
		)
		(pad "K1" smd circle
			(at -3.202 2.398 270)
			(size 0.43 0.43)
			(layers "F.Cu" "F.Mask" "F.Paste")
			(net 25 "+1V35")
			(pinfunction "VDD")
			(pintype "passive")
		)
		(pad "K2" smd circle
			(at -2.4 2.398 270)
			(size 0.43 0.43)
			(layers "F.Cu" "F.Mask" "F.Paste")
			(net 534 "/DRAM + SRAM/DDR.A3")
			(pinfunction "A3")
			(pintype "input")
		)
		(pad "K3" smd circle
			(at -1.601 2.398 270)
			(size 0.43 0.43)
			(layers "F.Cu" "F.Mask" "F.Paste")
			(net 531 "/DRAM + SRAM/DDR.A0")
			(pinfunction "A0")
			(pintype "input")
		)
		(pad "K7" smd circle
			(at 1.6 2.398 270)
			(size 0.43 0.43)
			(layers "F.Cu" "F.Mask" "F.Paste")
			(net 543 "/DRAM + SRAM/DDR.A12")
			(pinfunction "A12/BC#")
			(pintype "input")
		)
		(pad "K8" smd circle
			(at 2.398 2.398 270)
			(size 0.43 0.43)
			(layers "F.Cu" "F.Mask" "F.Paste")
			(net 548 "/DRAM + SRAM/DDR.BA1")
			(pinfunction "BA1")
			(pintype "input")
		)
		(pad "K9" smd circle
			(at 3.2 2.398 270)
			(size 0.43 0.43)
			(layers "F.Cu" "F.Mask" "F.Paste")
			(net 25 "+1V35")
			(pinfunction "VDD")
			(pintype "passive")
		)
		(pad "L1" smd circle
			(at -3.202 3.2 270)
			(size 0.43 0.43)
			(layers "F.Cu" "F.Mask" "F.Paste")
			(net 1 "GND")
			(pinfunction "VSS")
			(pintype "passive")
		)
		(pad "L2" smd circle
			(at -2.4 3.2 270)
			(size 0.43 0.43)
			(layers "F.Cu" "F.Mask" "F.Paste")
			(net 536 "/DRAM + SRAM/DDR.A5")
			(pinfunction "A5")
			(pintype "input")
		)
		(pad "L3" smd circle
			(at -1.601 3.2 270)
			(size 0.43 0.43)
			(layers "F.Cu" "F.Mask" "F.Paste")
			(net 533 "/DRAM + SRAM/DDR.A2")
			(pinfunction "A2")
			(pintype "input")
		)
		(pad "L7" smd circle
			(at 1.6 3.2 270)
			(size 0.43 0.43)
			(layers "F.Cu" "F.Mask" "F.Paste")
			(net 532 "/DRAM + SRAM/DDR.A1")
			(pinfunction "A1")
			(pintype "input")
		)
		(pad "L8" smd circle
			(at 2.398 3.2 270)
			(size 0.43 0.43)
			(layers "F.Cu" "F.Mask" "F.Paste")
			(net 535 "/DRAM + SRAM/DDR.A4")
			(pinfunction "A4")
			(pintype "input")
		)
		(pad "L9" smd circle
			(at 3.2 3.2 270)
			(size 0.43 0.43)
			(layers "F.Cu" "F.Mask" "F.Paste")
			(net 1 "GND")
			(pinfunction "VSS")
			(pintype "passive")
		)
		(pad "M1" smd circle
			(at -3.202 3.999 270)
			(size 0.43 0.43)
			(layers "F.Cu" "F.Mask" "F.Paste")
			(net 25 "+1V35")
			(pinfunction "VDD")
			(pintype "passive")
		)
		(pad "M2" smd circle
			(at -2.4 3.999 270)
			(size 0.43 0.43)
			(layers "F.Cu" "F.Mask" "F.Paste")
			(net 538 "/DRAM + SRAM/DDR.A7")
			(pinfunction "A7")
			(pintype "input")
		)
		(pad "M3" smd circle
			(at -1.601 3.999 270)
			(size 0.43 0.43)
			(layers "F.Cu" "F.Mask" "F.Paste")
			(net 540 "/DRAM + SRAM/DDR.A9")
			(pinfunction "A9")
			(pintype "input")
		)
		(pad "M7" smd circle
			(at 1.6 3.999 270)
			(size 0.43 0.43)
			(layers "F.Cu" "F.Mask" "F.Paste")
			(net 542 "/DRAM + SRAM/DDR.A11")
			(pinfunction "A11")
			(pintype "input")
		)
		(pad "M8" smd circle
			(at 2.398 3.999 270)
			(size 0.43 0.43)
			(layers "F.Cu" "F.Mask" "F.Paste")
			(net 537 "/DRAM + SRAM/DDR.A6")
			(pinfunction "A6")
			(pintype "input")
		)
		(pad "M9" smd circle
			(at 3.2 3.999 270)
			(size 0.43 0.43)
			(layers "F.Cu" "F.Mask" "F.Paste")
			(net 25 "+1V35")
			(pinfunction "VDD")
			(pintype "passive")
		)
		(pad "N1" smd circle
			(at -3.202 4.799 270)
			(size 0.43 0.43)
			(layers "F.Cu" "F.Mask" "F.Paste")
			(net 1 "GND")
			(pinfunction "VSS")
			(pintype "passive")
		)
		(pad "N2" smd circle
			(at -2.4 4.799 270)
			(size 0.43 0.43)
			(layers "F.Cu" "F.Mask" "F.Paste")
			(net 554 "/DRAM + SRAM/DDR.~{RESET}")
			(pinfunction "RESET#")
			(pintype "input")
		)
		(pad "N3" smd circle
			(at -1.601 4.799 270)
			(size 0.43 0.43)
			(layers "F.Cu" "F.Mask" "F.Paste")
			(net 544 "/DRAM + SRAM/DDR.A13")
			(pinfunction "A13")
			(pintype "input")
		)
		(pad "N7" smd circle
			(at 1.6 4.799 270)
			(size 0.43 0.43)
			(layers "F.Cu" "F.Mask" "F.Paste")
			(net 545 "/DRAM + SRAM/DDR.A14")
			(pinfunction "A14")
			(pintype "input")
		)
		(pad "N8" smd circle
			(at 2.398 4.799 270)
			(size 0.43 0.43)
			(layers "F.Cu" "F.Mask" "F.Paste")
			(net 539 "/DRAM + SRAM/DDR.A8")
			(pinfunction "A8")
			(pintype "input")
		)
		(pad "N9" smd circle
			(at 3.2 4.799 270)
			(size 0.43 0.43)
			(layers "F.Cu" "F.Mask" "F.Paste")
			(net 1 "GND")
			(pinfunction "VSS")
			(pintype "passive")
		)
	)
)
